(kicad_pcb
	(version 20260206)
	(generator "pcbnew")
	(generator_version "10.0")
	(general
		(thickness 1.6)
		(legacy_teardrops no)
	)
	(paper "A4")
	(title_block
		(title "Wiwynn_Tioga_Pass_MB.brd")
		(comment 1 "Tioga Pass / footprints 2718-2725 of 4770")
	)
	(layers
		(0 "F.Cu" signal "TOP")
		(4 "In1.Cu" signal "L2GND")
		(6 "In2.Cu" signal "L3")
		(8 "In3.Cu" signal "L4GND")
		(10 "In4.Cu" signal "L5")
		(12 "In5.Cu" signal "L6GND")
		(14 "In6.Cu" signal "L7VCC")
		(16 "In7.Cu" signal "L8VCC")
		(18 "In8.Cu" signal "L9GND")
		(20 "In9.Cu" signal "L10")
		(22 "In10.Cu" signal "L11GND")
		(24 "In11.Cu" signal "L12")
		(26 "In12.Cu" signal "L13GND")
		(2 "B.Cu" signal "BOTTOM")
		(9 "F.Adhes" user "F.Adhesive")
		(11 "B.Adhes" user "B.Adhesive")
		(13 "F.Paste" user "Package Geometry/Pastemask Top")
		(15 "B.Paste" user "Package Geometry/Pastemask Bottom")
		(5 "F.SilkS" user "Ref Des/Silkscreen Top")
		(7 "B.SilkS" user "Ref Des/Silkscreen Bottom")
		(1 "F.Mask" user "Board Geometry/Soldermask Top")
		(3 "B.Mask" user "Board Geometry/Soldermask Bottom")
		(17 "Dwgs.User" user "User.Drawings")
		(19 "Cmts.User" user "User.Comments")
		(21 "Eco1.User" user "User.Eco1")
		(23 "Eco2.User" user "User.Eco2")
		(25 "Edge.Cuts" user "Board Geometry/Outline")
		(27 "Margin" user)
		(31 "F.CrtYd" user "Package Geometry/Place Bound Top")
		(29 "B.CrtYd" user "Package Geometry/Place Bound Bottom")
		(35 "F.Fab" user "Ref Des/Assembly Top")
		(33 "B.Fab" user "Ref Des/Assembly Bottom")
	)
	(footprint ""
		(layer "B.Cu")
		(at 269.521686 -77.82814)
		(property "Reference" "C5P21"
			(at 0 0 0)
			(layer "B.SilkS")
			(hide yes)
			(effects
				(font
					(size 1.27 1.27)
				)
				(justify mirror)
			)
		)
		(property "Value" ""
			(at 0 0 0)
			(layer "B.Fab")
			(effects
				(font
					(size 1.27 1.27)
				)
				(justify mirror)
			)
		)
		(duplicate_pad_numbers_are_jumpers no)
		(fp_poly
			(pts
				(xy 0.7239 -0.2159) (xy -0.7239 -0.2159) (xy -0.7239 1.9939) (xy 0.7239 1.9939)
			)
			(stroke
				(width 0)
				(type default)
			)
			(fill no)
			(layer "B.CrtYd")
		)
		(fp_line
			(start -0.7239 -0.2159)
			(end 0.7239 -0.2159)
			(stroke
				(width 0.1)
				(type default)
			)
			(layer "B.Fab")
		)
		(fp_line
			(start -0.7239 1.9939)
			(end -0.7239 -0.2159)
			(stroke
				(width 0.1)
				(type default)
			)
			(layer "B.Fab")
		)
		(fp_line
			(start 0.7239 -0.2159)
			(end 0.7239 1.9939)
			(stroke
				(width 0.1)
				(type default)
			)
			(layer "B.Fab")
		)
		(fp_line
			(start 0.7239 1.9939)
			(end -0.7239 1.9939)
			(stroke
				(width 0.1)
				(type default)
			)
			(layer "B.Fab")
		)
		(pad "1" smd rect
			(at 0 0 180)
			(size 1.27 1.016)
			(layers "B.Cu" "B.Mask" "B.Paste")
			(net "PVCCMCP_CPU0")
		)
		(pad "2" smd rect
			(at 0 1.778 180)
			(size 1.27 1.016)
			(layers "B.Cu" "B.Mask" "B.Paste")
			(net "GND")
		)
		(zone
			(layer "B.Cu")
			(hatch none 0.5)
			(connect_pads
				(clearance 0)
			)
			(min_thickness 0.25)
			(keepout
				(tracks not_allowed)
				(vias allowed)
				(pads allowed)
				(copperpour not_allowed)
				(footprints allowed)
			)
			(placement
				(enabled no)
				(sheetname "")
			)
			(fill
				(thermal_gap 0.5)
				(thermal_bridge_width 0.5)
				(island_removal_mode 0)
			)
			(polygon
				(pts
					(xy 270.156686 -77.32014) (xy 268.886686 -77.32014) (xy 268.886686 -76.55814) (xy 270.156686 -76.55814)
				)
			)
		)
	)
	(footprint ""
		(layer "B.Cu")
		(at 276.000464 -12.954 90)
		(property "Reference" "C5G49"
			(at -1.14681 0.76708 180)
			(unlocked yes)
			(layer "B.SilkS")
			(effects
				(font
					(size 0.7874 0.5842)
					(thickness 0.1524)
				)
				(justify mirror)
			)
		)
		(property "Value" ""
			(at 0 0 90)
			(layer "B.Fab")
			(effects
				(font
					(size 1.27 1.27)
				)
				(justify mirror)
			)
		)
		(duplicate_pad_numbers_are_jumpers no)
		(fp_rect
			(start -0.4953 -0.2032)
			(end 0.4953 1.6002)
			(stroke
				(width 0)
				(type default)
			)
			(fill no)
			(layer "B.CrtYd")
		)
		(fp_line
			(start 0.4953 -0.2032)
			(end -0.4953 -0.2032)
			(stroke
				(width 0.1)
				(type default)
			)
			(layer "B.Fab")
		)
		(fp_line
			(start -0.4953 -0.2032)
			(end -0.4953 1.6002)
			(stroke
				(width 0.1)
				(type default)
			)
			(layer "B.Fab")
		)
		(fp_line
			(start 0.4953 1.6002)
			(end 0.4953 -0.2032)
			(stroke
				(width 0.1)
				(type default)
			)
			(layer "B.Fab")
		)
		(fp_line
			(start -0.4953 1.6002)
			(end 0.4953 1.6002)
			(stroke
				(width 0.1)
				(type default)
			)
			(layer "B.Fab")
		)
		(pad "1" smd rect
			(at 0 0 270)
			(size 0.762 0.889)
			(layers "B.Cu" "B.Mask" "B.Paste")
			(net "PVDDQ_ABC")
		)
		(pad "2" smd rect
			(at 0 1.397 270)
			(size 0.762 0.889)
			(layers "B.Cu" "B.Mask" "B.Paste")
			(net "GND")
		)
		(zone
			(layer "B.Cu")
			(hatch none 0.5)
			(connect_pads
				(clearance 0)
			)
			(min_thickness 0.25)
			(keepout
				(tracks not_allowed)
				(vias allowed)
				(pads allowed)
				(copperpour not_allowed)
				(footprints allowed)
			)
			(placement
				(enabled no)
				(sheetname "")
			)
			(fill
				(thermal_gap 0.5)
				(thermal_bridge_width 0.5)
				(island_removal_mode 0)
			)
			(polygon
				(pts
					(xy 276.444964 -12.573) (xy 276.952964 -12.573) (xy 276.952964 -13.335) (xy 276.444964 -13.335)
				)
			)
		)
	)
	(footprint ""
		(layer "B.Cu")
		(at 80.719168 -27.2034 90)
		(property "Reference" "C8T2"
			(at 0.96393 5.132832 0)
			(unlocked yes)
			(layer "B.SilkS")
			(effects
				(font
					(size 0.7874 0.5842)
					(thickness 0.1524)
				)
				(justify mirror)
			)
		)
		(property "Value" ""
			(at 0 0 90)
			(layer "B.Fab")
			(effects
				(font
					(size 1.27 1.27)
				)
				(justify mirror)
			)
		)
		(duplicate_pad_numbers_are_jumpers no)
		(fp_rect
			(start 0.500126 1.598422)
			(end -0.500126 -0.201422)
			(stroke
				(width 0)
				(type default)
			)
			(fill no)
			(layer "B.CrtYd")
		)
		(fp_line
			(start 0.500126 -0.201422)
			(end -0.500126 -0.201422)
			(stroke
				(width 0.1)
				(type default)
			)
			(layer "B.Fab")
		)
		(fp_line
			(start -0.500126 -0.201422)
			(end -0.500126 1.598422)
			(stroke
				(width 0.1)
				(type default)
			)
			(layer "B.Fab")
		)
		(fp_line
			(start 0.500126 1.598422)
			(end 0.500126 -0.201422)
			(stroke
				(width 0.1)
				(type default)
			)
			(layer "B.Fab")
		)
		(fp_line
			(start -0.500126 1.598422)
			(end 0.500126 1.598422)
			(stroke
				(width 0.1)
				(type default)
			)
			(layer "B.Fab")
		)
		(pad "1" smd rect
			(at 0 0)
			(size 0.889 0.9906)
			(layers "B.Cu" "B.Mask" "B.Paste")
			(net "PVDDQ_GHJ")
		)
		(pad "2" smd rect
			(at 0 1.397)
			(size 0.889 0.9906)
			(layers "B.Cu" "B.Mask" "B.Paste")
			(net "GND")
		)
		(zone
			(layer "B.Cu")
			(hatch none 0.5)
			(connect_pads
				(clearance 0)
			)
			(min_thickness 0.25)
			(keepout
				(tracks allowed)
				(vias not_allowed)
				(pads allowed)
				(copperpour not_allowed)
				(footprints allowed)
			)
			(placement
				(enabled no)
				(sheetname "")
			)
			(fill
				(thermal_gap 0.5)
				(thermal_bridge_width 0.5)
				(island_removal_mode 0)
			)
			(polygon
				(pts
					(xy 81.671668 -27.6987) (xy 81.163668 -27.6987) (xy 81.163668 -26.7081) (xy 81.671668 -26.7081)
				)
			)
		)
		(zone
			(layer "B.Cu")
			(hatch none 0.5)
			(connect_pads
				(clearance 0)
			)
			(min_thickness 0.25)
			(keepout
				(tracks not_allowed)
				(vias allowed)
				(pads allowed)
				(copperpour not_allowed)
				(footprints allowed)
			)
			(placement
				(enabled no)
				(sheetname "")
			)
			(fill
				(thermal_gap 0.5)
				(thermal_bridge_width 0.5)
				(island_removal_mode 0)
			)
			(polygon
				(pts
					(xy 81.671668 -27.6987) (xy 81.163668 -27.6987) (xy 81.163668 -26.7081) (xy 81.671668 -26.7081)
				)
			)
		)
	)
	(footprint ""
		(layer "B.Cu")
		(at 94.271592 -82.001614)
		(property "Reference" "C8P7"
			(at 0 0 0)
			(layer "B.SilkS")
			(hide yes)
			(effects
				(font
					(size 1.27 1.27)
				)
				(justify mirror)
			)
		)
		(property "Value" ""
			(at 0 0 0)
			(layer "B.Fab")
			(effects
				(font
					(size 1.27 1.27)
				)
				(justify mirror)
			)
		)
		(duplicate_pad_numbers_are_jumpers no)
		(fp_poly
			(pts
				(xy 0.7239 -0.2159) (xy -0.7239 -0.2159) (xy -0.7239 1.9939) (xy 0.7239 1.9939)
			)
			(stroke
				(width 0)
				(type default)
			)
			(fill no)
			(layer "B.CrtYd")
		)
		(fp_line
			(start -0.7239 -0.2159)
			(end 0.7239 -0.2159)
			(stroke
				(width 0.1)
				(type default)
			)
			(layer "B.Fab")
		)
		(fp_line
			(start -0.7239 1.9939)
			(end -0.7239 -0.2159)
			(stroke
				(width 0.1)
				(type default)
			)
			(layer "B.Fab")
		)
		(fp_line
			(start 0.7239 -0.2159)
			(end 0.7239 1.9939)
			(stroke
				(width 0.1)
				(type default)
			)
			(layer "B.Fab")
		)
		(fp_line
			(start 0.7239 1.9939)
			(end -0.7239 1.9939)
			(stroke
				(width 0.1)
				(type default)
			)
			(layer "B.Fab")
		)
		(pad "1" smd rect
			(at 0 0 180)
			(size 1.27 1.016)
			(layers "B.Cu" "B.Mask" "B.Paste")
			(net "PVSA_CPU1")
		)
		(pad "2" smd rect
			(at 0 1.778 180)
			(size 1.27 1.016)
			(layers "B.Cu" "B.Mask" "B.Paste")
			(net "GND")
		)
		(zone
			(layer "B.Cu")
			(hatch none 0.5)
			(connect_pads
				(clearance 0)
			)
			(min_thickness 0.25)
			(keepout
				(tracks not_allowed)
				(vias allowed)
				(pads allowed)
				(copperpour not_allowed)
				(footprints allowed)
			)
			(placement
				(enabled no)
				(sheetname "")
			)
			(fill
				(thermal_gap 0.5)
				(thermal_bridge_width 0.5)
				(island_removal_mode 0)
			)
			(polygon
				(pts
					(xy 94.906592 -81.493614) (xy 93.636592 -81.493614) (xy 93.636592 -80.731614) (xy 94.906592 -80.731614)
				)
			)
		)
	)
	(footprint ""
		(layer "B.Cu")
		(at 367.827814 -124.389642 -90)
		(property "Reference" "R783"
			(at 0.8382 -0.67818 270)
			(unlocked yes)
			(layer "B.SilkS")
			(effects
				(font
					(size 0.4064 0.254)
					(thickness 0.1524)
				)
				(justify left mirror)
			)
		)
		(property "Value" ""
			(at 0 0 90)
			(layer "B.Fab")
			(effects
				(font
					(size 1.27 1.27)
				)
				(justify mirror)
			)
		)
		(duplicate_pad_numbers_are_jumpers no)
		(fp_poly
			(pts
				(xy 0.2794 -0.1016) (xy -0.2794 -0.1016) (xy -0.2794 0.9906) (xy 0.2794 0.9906)
			)
			(stroke
				(width 0)
				(type default)
			)
			(fill no)
			(layer "B.CrtYd")
		)
		(fp_line
			(start -0.2794 0.9906)
			(end -0.2794 -0.1016)
			(stroke
				(width 0.1)
				(type default)
			)
			(layer "B.Fab")
		)
		(fp_line
			(start 0.2794 0.9906)
			(end -0.2794 0.9906)
			(stroke
				(width 0.1)
				(type default)
			)
			(layer "B.Fab")
		)
		(fp_line
			(start -0.2794 -0.1016)
			(end 0.2794 -0.1016)
			(stroke
				(width 0.1)
				(type default)
			)
			(layer "B.Fab")
		)
		(fp_line
			(start 0.2794 -0.1016)
			(end 0.2794 0.9906)
			(stroke
				(width 0.1)
				(type default)
			)
			(layer "B.Fab")
		)
		(pad "1" smd rect
			(at 0 0 90)
			(size 0.508 0.508)
			(layers "B.Cu" "B.Mask" "B.Paste")
			(net "P3E_CPU0_PE1_PCH_RXP<9>")
		)
		(pad "2" smd rect
			(at 0 0.889 90)
			(size 0.508 0.508)
			(layers "B.Cu" "B.Mask" "B.Paste")
			(net "P3E_CPU0_PE1_PCH_CON_RXP<9>")
		)
		(zone
			(layer "B.Cu")
			(hatch none 0.5)
			(connect_pads
				(clearance 0)
			)
			(min_thickness 0.25)
			(keepout
				(tracks not_allowed)
				(vias allowed)
				(pads allowed)
				(copperpour not_allowed)
				(footprints allowed)
			)
			(placement
				(enabled no)
				(sheetname "")
			)
			(fill
				(thermal_gap 0.5)
				(thermal_bridge_width 0.5)
				(island_removal_mode 0)
			)
			(polygon
				(pts
					(xy 367.192814 -124.135642) (xy 367.192814 -124.643642) (xy 367.573814 -124.643642) (xy 367.573814 -124.135642)
				)
			)
		)
		(zone
			(layer "B.Cu")
			(hatch none 0.5)
			(connect_pads
				(clearance 0)
			)
			(min_thickness 0.25)
			(keepout
				(tracks allowed)
				(vias not_allowed)
				(pads allowed)
				(copperpour not_allowed)
				(footprints allowed)
			)
			(placement
				(enabled no)
				(sheetname "")
			)
			(fill
				(thermal_gap 0.5)
				(thermal_bridge_width 0.5)
				(island_removal_mode 0)
			)
			(polygon
				(pts
					(xy 367.573814 -124.135642) (xy 367.573814 -124.643642) (xy 367.192814 -124.643642) (xy 367.192814 -124.135642)
				)
			)
		)
	)
	(footprint ""
		(layer "B.Cu")
		(at 2.1082 -50.1142 -90)
		(property "Reference" "C9R12"
			(at 0 0 90)
			(layer "B.SilkS")
			(hide yes)
			(effects
				(font
					(size 1.27 1.27)
				)
				(justify mirror)
			)
		)
		(property "Value" ""
			(at 0 0 90)
			(layer "B.Fab")
			(effects
				(font
					(size 1.27 1.27)
				)
				(justify mirror)
			)
		)
		(duplicate_pad_numbers_are_jumpers no)
		(fp_rect
			(start 0.3048 -0.1016)
			(end -0.3048 0.9906)
			(stroke
				(width 0)
				(type default)
			)
			(fill no)
			(layer "B.CrtYd")
		)
		(fp_line
			(start -0.3048 0.9906)
			(end -0.3048 -0.1016)
			(stroke
				(width 0.1)
				(type default)
			)
			(layer "B.Fab")
		)
		(fp_line
			(start 0.3048 0.9906)
			(end -0.3048 0.9906)
			(stroke
				(width 0.1)
				(type default)
			)
			(layer "B.Fab")
		)
		(fp_line
			(start -0.3048 -0.1016)
			(end 0.3048 -0.1016)
			(stroke
				(width 0.1)
				(type default)
			)
			(layer "B.Fab")
		)
		(fp_line
			(start 0.3048 -0.1016)
			(end 0.3048 0.9906)
			(stroke
				(width 0.1)
				(type default)
			)
			(layer "B.Fab")
		)
		(pad "1" smd rect
			(at 0 0 90)
			(size 0.508 0.508)
			(layers "B.Cu" "B.Mask" "B.Paste")
			(net "P12V_PSU")
		)
		(pad "2" smd rect
			(at 0 0.889 90)
			(size 0.508 0.508)
			(layers "B.Cu" "B.Mask" "B.Paste")
			(net "GND")
		)
		(zone
			(layer "B.Cu")
			(hatch none 0.5)
			(connect_pads
				(clearance 0)
			)
			(min_thickness 0.25)
			(keepout
				(tracks not_allowed)
				(vias allowed)
				(pads allowed)
				(copperpour not_allowed)
				(footprints allowed)
			)
			(placement
				(enabled no)
				(sheetname "")
			)
			(fill
				(thermal_gap 0.5)
				(thermal_bridge_width 0.5)
				(island_removal_mode 0)
			)
			(polygon
				(pts
					(xy 1.8542 -49.8602) (xy 1.8542 -50.3682) (xy 1.4732 -50.3682) (xy 1.4732 -49.8602)
				)
			)
		)
		(zone
			(layer "B.Cu")
			(hatch none 0.5)
			(connect_pads
				(clearance 0)
			)
			(min_thickness 0.25)
			(keepout
				(tracks allowed)
				(vias not_allowed)
				(pads allowed)
				(copperpour not_allowed)
				(footprints allowed)
			)
			(placement
				(enabled no)
				(sheetname "")
			)
			(fill
				(thermal_gap 0.5)
				(thermal_bridge_width 0.5)
				(island_removal_mode 0)
			)
			(polygon
				(pts
					(xy 1.8542 -49.8602) (xy 1.8542 -50.3682) (xy 1.4732 -50.3682) (xy 1.4732 -49.8602)
				)
			)
		)
	)
	(footprint ""
		(layer "B.Cu")
		(at 390.635744 -24.169116 -90)
		(property "Reference" "C2T21"
			(at 0 0 90)
			(layer "B.SilkS")
			(hide yes)
			(effects
				(font
					(size 1.27 1.27)
				)
				(justify mirror)
			)
		)
		(property "Value" ""
			(at 0 0 90)
			(layer "B.Fab")
			(effects
				(font
					(size 1.27 1.27)
				)
				(justify mirror)
			)
		)
		(duplicate_pad_numbers_are_jumpers no)
		(fp_poly
			(pts
				(xy -0.3048 -0.1016) (xy -0.3048 0.9906) (xy 0.3048 0.9906) (xy 0.3048 -0.1016)
			)
			(stroke
				(width 0)
				(type default)
			)
			(fill no)
			(layer "B.CrtYd")
		)
		(fp_line
			(start -0.3048 0.9906)
			(end -0.3048 -0.1016)
			(stroke
				(width 0.1)
				(type default)
			)
			(layer "B.Fab")
		)
		(fp_line
			(start 0.3048 0.9906)
			(end -0.3048 0.9906)
			(stroke
				(width 0.1)
				(type default)
			)
			(layer "B.Fab")
		)
		(fp_line
			(start -0.3048 -0.1016)
			(end 0.3048 -0.1016)
			(stroke
				(width 0.1)
				(type default)
			)
			(layer "B.Fab")
		)
		(fp_line
			(start 0.3048 -0.1016)
			(end 0.3048 0.9906)
			(stroke
				(width 0.1)
				(type default)
			)
			(layer "B.Fab")
		)
		(pad "1" smd rect
			(at 0 0 90)
			(size 0.508 0.508)
			(layers "B.Cu" "B.Mask" "B.Paste")
			(net "P3V3")
		)
		(pad "2" smd rect
			(at 0 0.889 90)
			(size 0.508 0.508)
			(layers "B.Cu" "B.Mask" "B.Paste")
			(net "GND")
		)
		(zone
			(layer "B.Cu")
			(hatch none 0.5)
			(connect_pads
				(clearance 0)
			)
			(min_thickness 0.25)
			(keepout
				(tracks not_allowed)
				(vias allowed)
				(pads allowed)
				(copperpour not_allowed)
				(footprints allowed)
			)
			(placement
				(enabled no)
				(sheetname "")
			)
			(fill
				(thermal_gap 0.5)
				(thermal_bridge_width 0.5)
				(island_removal_mode 0)
			)
			(polygon
				(pts
					(xy 390.000744 -23.915116) (xy 390.000744 -24.423116) (xy 390.381744 -24.423116) (xy 390.381744 -23.915116)
				)
			)
		)
		(zone
			(layer "B.Cu")
			(hatch none 0.5)
			(connect_pads
				(clearance 0)
			)
			(min_thickness 0.25)
			(keepout
				(tracks allowed)
				(vias not_allowed)
				(pads allowed)
				(copperpour not_allowed)
				(footprints allowed)
			)
			(placement
				(enabled no)
				(sheetname "")
			)
			(fill
				(thermal_gap 0.5)
				(thermal_bridge_width 0.5)
				(island_removal_mode 0)
			)
			(polygon
				(pts
					(xy 390.381744 -23.915116) (xy 390.381744 -24.423116) (xy 390.000744 -24.423116) (xy 390.000744 -23.915116)
				)
			)
		)
	)
	(footprint ""
		(layer "B.Cu")
		(at 415.4805 -29.337 90)
		(property "Reference" "C25W37"
			(at 0.8382 -0.67818 90)
			(unlocked yes)
			(layer "B.SilkS")
			(effects
				(font
					(size 0.4064 0.254)
					(thickness 0.1524)
				)
				(justify left mirror)
			)
		)
		(property "Value" ""
			(at 0 0 90)
			(layer "B.Fab")
			(effects
				(font
					(size 1.27 1.27)
				)
				(justify mirror)
			)
		)
		(duplicate_pad_numbers_are_jumpers no)
		(fp_poly
			(pts
				(xy -0.3048 -0.1016) (xy -0.3048 0.9906) (xy 0.3048 0.9906) (xy 0.3048 -0.1016)
			)
			(stroke
				(width 0)
				(type default)
			)
			(fill no)
			(layer "B.CrtYd")
		)
		(fp_line
			(start 0.3048 -0.1016)
			(end 0.3048 0.9906)
			(stroke
				(width 0.1)
				(type default)
			)
			(layer "B.Fab")
		)
		(fp_line
			(start -0.3048 -0.1016)
			(end 0.3048 -0.1016)
			(stroke
				(width 0.1)
				(type default)
			)
			(layer "B.Fab")
		)
		(fp_line
			(start 0.3048 0.9906)
			(end -0.3048 0.9906)
			(stroke
				(width 0.1)
				(type default)
			)
			(layer "B.Fab")
		)
		(fp_line
			(start -0.3048 0.9906)
			(end -0.3048 -0.1016)
			(stroke
				(width 0.1)
				(type default)
			)
			(layer "B.Fab")
		)
		(pad "1" smd rect
			(at 0 0 270)
			(size 0.508 0.508)
			(layers "B.Cu" "B.Mask" "B.Paste")
			(net "VCC_A_1V1")
		)
		(pad "2" smd rect
			(at 0 0.889 270)
			(size 0.508 0.508)
			(layers "B.Cu" "B.Mask" "B.Paste")
			(net "GND")
		)
		(zone
			(layer "B.Cu")
			(hatch none 0.5)
			(connect_pads
				(clearance 0)
			)
			(min_thickness 0.25)
			(keepout
				(tracks allowed)
				(vias not_allowed)
				(pads allowed)
				(copperpour not_allowed)
				(footprints allowed)
			)
			(placement
				(enabled no)
				(sheetname "")
			)
			(fill
				(thermal_gap 0.5)
				(thermal_bridge_width 0.5)
				(island_removal_mode 0)
			)
			(polygon
				(pts
					(xy 415.7345 -29.591) (xy 415.7345 -29.083) (xy 416.1155 -29.083) (xy 416.1155 -29.591)
				)
			)
		)
		(zone
			(layer "B.Cu")
			(hatch none 0.5)
			(connect_pads
				(clearance 0)
			)
			(min_thickness 0.25)
			(keepout
				(tracks not_allowed)
				(vias allowed)
				(pads allowed)
				(copperpour not_allowed)
				(footprints allowed)
			)
			(placement
				(enabled no)
				(sheetname "")
			)
			(fill
				(thermal_gap 0.5)
				(thermal_bridge_width 0.5)
				(island_removal_mode 0)
			)
			(polygon
				(pts
					(xy 416.1155 -29.591) (xy 416.1155 -29.083) (xy 415.7345 -29.083) (xy 415.7345 -29.591)
				)
			)
		)
	)
)
